 
 
Open CloudServer  
network mezzanine I/O 
specification 
V1.0 
 
Authors: 
Mark Shaw, Director of Hardware Engineering, Microsoft 
Martin Goldstein, Principal Systems Architect, Microsoft  


 
2 January 28, 2014 
1 Revision History 
 
Date Name Description 
1/28/2014  Version 1.0 
   
   
   
   
   
   
   
 
  



Open Compute Project  Open CloudServer network mezzanine I/O specification 
http://opencompute.org 3 
© 2014 Microsoft Corporation. 
 
As of January 28, 2014, the following persons or entities have made this Specification available under 
the Open Web Foundation Final Specification Agreement (OWFa 1.0), which is available at 
http://www.openwebfoundation.org/legal/the-owf-1-0-agreements/owfa-1-0 Microsoft Corporation.  
You can review the signed copies of the Open Web Foundation Agreement Version 1.0 for this 
Specification at http://opencompute.org/licensing/, which may also include additional parties to those 
listed above. 
Your use of this Specification may be subject to other third party rights. THIS SPECIFICATION IS 
PROVIDED "AS IS." The contributors expressly disclaim any warranties (express, implied, or otherwise), 
including implied warranties of merchantability, noninfringement, fitness for a particular purpose, or title, 
related to the Specification. The entire risk as to implementing or otherwise using the Specification is 
assumed by the Specification implementer and user. IN NO EVENT WILL ANY PARTY BE LIABLE TO ANY 
OTHER PARTY FOR LOST PROFITS OR ANY FORM OF INDIRECT, SPECIAL, INCIDENTAL, OR 
CONSEQUENTIAL DAMAGES OF ANY CHARACTER FROM ANY CAUSES OF ACTION OF ANY KIND WITH 
RESPECT TO THIS SPECIFICATION OR ITS GOVERNING AGREEMENT, WHETHER BASED ON BREACH OF 
CONTRACT, TORT (INCLUDING NEGLIGENCE), OR OTHERWISE, AND WHETHER OR NOT THE OTHER 
PARTY HAS BEEN ADVISED OF THE POSSIBILITY OF SUCH DAMAGE. 
CONTRIBUTORS AND LICENSORS OF THIS SPECIFICATION MAY HAVE MENTIONED CERTAIN 
TECHNOLOGIES THAT ARE MERELY REFERENCED WITHIN THIS SPECIFICATION AND NOT LICENSED 
UNDER THE OWF CLA OR OWFa. THE FOLLOWING IS A LIST OF MERELY REFERENCED TECHNOLOGY: 
INTELLIGENT PLATFORM MANAGEMENT INTERFACE (IPMI), I2C TRADEMARK OF PHILLIPS 
SEMICONDUCTOR. IMPLEMENTATION OF THESE TECHNOLOGIES MAY BE SUBJECT TO THEIR OWN 
LEGAL TERMS.  



 
4 January 28, 2014 
2 Scope 
This document focuses on the Open CloudServer system network mezzanine 
input/output (I/O). 
3 Contents 
1 Revision History ......................................................................................................................... 2 
2 Scope ......................................................................................................................................... 4 
3 Contents .................................................................................................................................... 4 
4 Overview.................................................................................................................................... 5 
5 Signaling Interface ..................................................................................................................... 5 
5.1 Ethernet Port Mapping ................................................................................................. 6 
5.2 Connectors ................................................................................................................... 6 
5.3 Signal Definitions .......................................................................................................... 7 
5.4 Connector Pinout ......................................................................................................... 8 
6 Power ........................................................................................................................................ 9 
7 Mechanical .............................................................................................................................. 10 
8 Thermal ................................................................................................................................... 11 
9 Appendix: Commonly Used Acronyms .................................................................................... 12 
 
  



Open Compute Project  Open CloudServer network mezzanine I/O specification 
http://opencompute.org 5 
4 Overview 
This document outlines specifications for the Open CloudServer mezzanine network 
interface card (NIC). The NIC interfaces to the processor via PCI-Express (PCIe) Gen3 
x8 I/O bus and dual 10 Gbit Ethernet. Single and dual 10 Gbit Ethernet are 
supported. Dual 40 Gbit Ethernet pins have been defined for potential future use. 
Figure 1 shows a block diagram of the network mezzanine I/O. 
 
Figure 1. Network Mezzanine I/O connectivity 
The compute blade uses the following retimers: 
 4-channel: TI DS110RT410; 7x7mm 48-pin quad-flat no-leads (QFN) package 
5 Signaling Interface 
The networking mezzanine interface has been defined to provide high bandwidth 
and a flexible interface. The card receives a PCI-Express Gen3 x8 bus from the CPU. 
The supported output networks include: 
 1 x 10G Ethernet 


 
6 January 28, 2014 
 2 x 10G Ethernet 
5.1 Ethernet Port Mapping 
Table 1 shows the mappings of the networking signals to the backplane. 
Table 1. Network Mezzanine Port to Connector Mapping 
Networking signals 10G blade signal names 10G tray signal names 
NWK_1_TX/RX0 ENET10G_1_TD/RD ENET10G_1_TD/RD 
SFP+ #1 
NWK_1_TX/RX[1:3] Not connected Not connected 
NWK_2_TX/RX0 ENET10G_2_TD/RD ENET10G_2_TD/RD 
SFP+ #2 
NWK_2_TX/RX[1:3] Not connected Not connected 
5.2 Connectors 
Table 2 shows the connector part numbers for the network mezzanine card. 
Table 2. Connector Part Numbers, Network Mezzanine Card 
Manufacturer Card connector MPN Motherboard connector MPN 
Samtec SEAM-20-03.5-L-08-2-A-K-TR SEAF-20-06.5-L-08-2-A-K-TR 
Molex 45970-2385 45971-2385 
The stackup height of the SEAM is 10mm with a 6.5mm SEAF and a 3.5mm SEAM 
connector. In this configuration, it is expected that taller components will be place on 
the top side of the printed circuit board (PCB), as shown in Figure 2. 



Open Compute Project  Open CloudServer network mezzanine I/O specification 
http://opencompute.org 7 
SEAF6.5mm
3.5mm
10mm
Device
Heatsink
Backside Keepout
SEAM
 
Figure 2. Connector stackup 
5.3 Signal Definitions 
Table 3 defines the signals used in the NIC mezzanine interface. 
Table 3. NIC Mezzanine Connector Signal Definitions 
Bus type I/O Logic Definition 
P3E_CPU1_LAN_RX_DP/N[7:0] O CML PCIe Gen3 from the NIC Mezz to the CPU 
P3E_CPU1_LAN_TX_DP/N[7:0] I CML PCIe Gen3 from the CPU to the NIC Mezz 
CLK_100M_NIC_PE_DP/N I CML 100MHz PCIe Clock 
PCIE_RESET_N I 3.3V PCIe Reset 
MEZZ_PRESENT_N O 3.3V Mezz Present – Should be GND on Mezzanine 
NWK_1_TX[3:0]P/N O CML Port 1 GbE Transmit from Mezz to Motherboard 
NWK_1_RX[3:0]P/N I CML Port 1 GbE Receive from Motherboard to Mezz 
NWK_2_TX[3:0]P/N O CML Port 2 GbE Transmit from Mezz to Motherboard 
NWK_2_RX[3:0]P/N I CML Port 2 GbE Receive from Motherboard to Mezz 
SMB_ALERT_N O 3.3V I2C Alert from NIC Mezz to BMC 
NWK1_PRESENT_N I 3.3V Port 1 Cable Present Indicator 
NWK1_I2C_SDA I/O 3.3V Port1 I2C Data to Cable 
NWK1_I2C_CLK O 3.3V Port 1 I2C Clock to Cable 



 
8 January 28, 2014 
Bus type I/O Logic Definition 
NWK2_PRESENT_N I 3.3V Port 2 Cable Present Indicator 
NWK2_I2C_SDA I/O 3.3V Port 2 I2C Data to Cable 
NWK2_I2C_SCL O 3.3V I2C to QSFP+ Cable 
PCIE_WAKE_N O 3.3V PCIe Wake 
SMB_SCL I 3.3V I2C to BMC 
SMB_SDA I/O 3.3V I2C to BMC 
NIC_MEZZ_ID[1:0] O 3.3V 
NIC Mezz ID – Connected to BMC on motherboard 
NIC_MEZZ_ID[1:0] definition is: TBD 
P3V3 I 3.3V 3.3V Input Power 
P3V3_AUX I 3.3V 3.3V Aux Input Power 
P12V_AUX I 12V 12V Input Power 
Ground   Ground Pins 
5.4 Connector Pinout 
Table 4 lists the pinout for the 160-pin connector on the tray mezzanine card that 
interfaces to the tray backplane. 
Table 4. NIC Mezzanine Connector Pinout 
1 GND PCIE_RESET_
N GND PCIE_WAKE_
N 
NIC_MEZZ_I
D0 
SMB_ALERT_
N GND 
CLK_100
M_NIC_P
E_DP 
8 
9 
P3E_CPU1_L
AN_TX_C_DP
<0> 
GND 
P3E_CPU1_L
AN_RX_C_DP
<7> 
GND SMB_SCL NWK1_PRES
ENT_N GND 
CLK_100
M_NIC_P
E_DN 
16 
17 
P3E_CPU1_L
AN_TX_C_DN
<0> 
GND 
P3E_CPU1_L
AN_RX_C_D
N<7> 
GND SMB_SDA GND MEZZ_PR
ESENT_N GND 24 
25 GND 
P3E_CPU1_L
AN_TX_C_DP
<1> 
GND 
P3E_CPU1_L
AN_RX_C_DP
<6> 
GND NWK_1_TX1P GND NWK_2_
TX0P 32 



Open Compute Project  Open CloudServer network mezzanine I/O specification 
http://opencompute.org 9 
33 GND 
P3E_CPU1_L
AN_TX_C_DN
<1> 
GND 
P3E_CPU1_L
AN_RX_C_D
N<6> 
GND NWK_1_TX1
N GND NWK_2_
TX0N 40 
41 
P3E_CPU1_L
AN_TX_C_DP
<2> 
GND 
P3E_CPU1_L
AN_RX_C_DP
<5> 
GND NWK_1_TX2P GND NWK_2_T
X1P GND 48 
49 
P3E_CPU1_L
AN_TX_C_DN
<2> 
GND 
P3E_CPU1_L
AN_RX_C_D
N<5> 
GND NWK_1_TX2
N GND NWK_2_T
X1N GND 56 
57 GND 
P3E_CPU1_L
AN_TX_C_DP
<3> 
GND 
P3E_CPU1_L
AN_RX_C_DP
<4> 
GND NWK_1_TX3P GND NWK_2_
TX2P 64 
65 GND 
P3E_CPU1_L
AN_TX_C_DN
<3> 
GND 
P3E_CPU1_L
AN_RX_C_D
N<4> 
GND NWK_1_TX3
N GND NWK_2_
TX2N 72 
73 
P3E_CPU1_L
AN_TX_C_DP
<4> 
GND 
P3E_CPU1_L
AN_RX_C_DP
<0> 
GND NWK_1_RX1
N GND NWK_2_T
X3P GND 80 
81 
P3E_CPU1_L
AN_TX_C_DN
<4> 
GND 
P3E_CPU1_L
AN_RX_C_D
N<0> 
GND NWK_1_RX1
P GND NWK_2_T
X3N GND 88 
89 GND 
P3E_CPU1_L
AN_TX_C_DP
<5> 
GND 
P3E_CPU1_L
AN_RX_C_DP
<1> 
GND NWK_1_RX2
N GND NWK_2_
RX0P 96 
97 GND 
P3E_CPU1_L
AN_TX_C_DN
<5> 
GND 
P3E_CPU1_L
AN_RX_C_D
N<1> 
GND NWK_1_RX2
P GND NWK_2_
RX0N 104 
105 
P3E_CPU1_L
AN_TX_C_DP
<6> 
GND 
P3E_CPU1_L
AN_RX_C_DP
<2> 
GND NWK_1_RX3
N GND NWK_2_R
X1N GND 112 
113 
P3E_CPU1_L
AN_TX_C_DN
<6> 
GND 
P3E_CPU1_L
AN_RX_C_D
N<2> 
GND NWK_1_RX3
P GND NWK_2_R
X1P GND 120 
121 GND 
P3E_CPU1_L
AN_TX_C_DP
<7> 
GND 
P3E_CPU1_L
AN_RX_C_DP
<3> 
GND NWK_1_TX0P GND NWK_2_
RX2N 128 
129 NWK1_I2C_S
DA 
P3E_CPU1_L
AN_TX_C_DN
<7> 
GND 
P3E_CPU1_L
AN_RX_C_D
N<3> 
GND NWK_1_TX0
N GND NWK_2_
RX2P 136 
137 NWK1_I2C_S
CL GND NIC_MEZZ_I
D1 GND NWK_1_RX0
P GND NWK_2_R
X3N GND 144 
145 P12V_AUX P3V3_AUX P3V3 GND NWK_1_RX0
N GND NWK_2_R
X3P 
NWK2_I2
C_SDA 152 
153 P12V_AUX P3V3_AUX P3V3 P3V3 GND NWK2_PRES
ENT_N GND NWK2_I2
C_SCL 160 
6 Power 
Table 5 specifies the local area network (LAN) mezzanine power ratings for the rail. 



 
10 January 28, 2014 
Table 5. LAN Mezzanine Power Ratings 
Power rails Amps/pin (at 
40oC) 
Total number 
of pins 
Power load capacity 
by connector pins (W) 
Motherboard limited 
power budget (W) 
12V_AUX 2A 2 43.2W 25.2W 
3.3V_AUX 2A 2 11.88W 1.2375W 
3.3V 2A 3 17.82W 9.9W 
Total power budget (per mezzanine card) 25W 
Figure 3 shows the LAN mezzanine power-up sequence. 
 
Figure 3. LAN mezzanine power-up sequence 
Note that the maximum power consumption of the mezzanine cards is 25W. The 
reset signal conforms to the PCI Express reset specifications. 
7 Mechanical 
Figure 4 shows the dimensions of the network mezzanine. Note that PCB board 
thickness can vary as long as the keep-in volumes are not violated. 


Open Compute Project  Open CloudServer network mezzanine I/O specification 
http://opencompute.org 11 
 `
  
Figure 4. Network mezzanine dimensions 
8 Thermal 
The network mezzanine cards are designed to be located at the extreme downstream 
position of the server, so the air is heated by all of the upstream components before 
reaching the cards. The direction of air flow is shown in Figure 4.   
Table 6 shows the worst-case environmental conditions that can be expected at the 
network mezzanine card inlet. The thermal solution and component selection should 
be sufficient for these conditions.  



 
12 January 28, 2014 
Table 6. Environmental Operating Conditions, Network Mezzanine Card 
Variable Worst case operating condition 
Approaching airflow rate 200 ft/min, uniform 
Maximum allowable pressure drop across card 0.040 “H2O max at 200 ft/min 
Approaching airflow temperature 66OC 
9 Appendix: Commonly Used Acronyms 
This section provides definitions of acronyms used in the system specifications. 
ACPI – advanced configuration and 
power interface  
AHCI – advanced host controller 
interface 
AHJ – authority having jurisdiction 
ANSI – American National 
Standards Institute 
API – application programming 
interface 
ASHRAE – American Society of 
Heating, Refrigerating and Air 
Conditioning Engineers 
ASIC – application-specific 
integrated circuit 
BCD – binary-coded decimal 
BIOS – basic input/output system 
BMC – baseboard management 
controller 
CFM – cubic feet per minute 
(measure of volume flow rate) 
CM – Chassis Manager 
CMOS – complementary metal–
oxide–semiconductor 
COLO – co-location 
CTS – clear to send 
DCMI – data center manageability 
interface 
DDR3 – double data rate type 3  
DHCP – dynamic host 
configuration protocol 
DIMM – dual inline memory 
module  
DPC - DIMMs per memory channel  
DRAM – dynamic random access 
memory 
DSR – data set ready 
DTR – data terminal ready 
ECC – error-correcting code 
EEPROM - electrically erasable 
programmable read-only memory 
EIA – Electronic Industries Alliance 
EMC – electromagnetic 
compatibility 
EMI – electromagnetic interference 
FRU – field replaceable unit 



Open Compute Project  Open CloudServer network mezzanine I/O specification 
http://opencompute.org 13 
FTP – file transfer protocol 
GPIO – general purpose input 
output 
GUID – globally unique identifier 
HBI – high business intelligence 
HCK – Windows Hardware 
Certification Kit 
HMD – hardware monitoring 
device 
HT – hyperthreading 
I2C – inter-integrated circuit 
IBC – international building code 
IDE – integrated development 
environment 
IEC - International Electrotechnical 
Commission 
IOC – I/O controller 
IPMI – intelligent platform 
management interface 
IPsec – IP security 
ITPAC – IT pre-assembled 
components 
JBOD – “just a bunch of disks” 
KCS – keyboard controller style 
L2 – layer 2 
LAN – local area network 
LFF – large form factor 
LPC – low pin count 
LS – least significant 
LUN – logical unit number 
MAC – media access control 
MDC – modular data center 
containers 
MLC – multi-level call 
MTBF – mean time between 
failures  
MUX – multiplexer 
NIC – network interface card 
NUMA – non-uniform memory 
access 
OOB – out of band 
OSHA - Occupational Safety & 
Health Administration 
OTS – off the shelf 
PCB – printed circuit board 
PCIe – peripheral component 
interconnect express 
PCH – platform control hub 
PDB – power distribution 
backplane 
PDU – power distribution unit 
Ph-ph – phase to phase 
Ph-N – phase to neutral 
PNP – plug and play 
POST – power-on self-test 
PSU – power supply unit 
PWM – pulse-width modulation 
PXE – preboot execution 
environment 
QDR – quad data rate 
QFN – quad flat package no-lead 
QPI – Intel QuickPath Interconnect 
QSFP – quad small form-factor 
pluggable 
RAID – redundant array of 
independent disks 



 
14 January 28, 2014 
REST - representational state 
transfer 
RM – rack manager 
RMA – remote management agent 
ROC – RAID-on-chip controller 
RSS – receive-side scaling 
RTS – request to send 
RU – rack unit 
RxD – received data 
SAS – serial-attached small 
computer system interface (SCSI) 
SATA – serial AT attachment 
SCK – serial clock 
SCSI – small computer system 
interface 
SDA – serial data signal 
SDR – sensor data record 
SFF – small form factor 
SFP – small form-factor pluggable  
SMBUS – systems management 
bus 
SMBIOS – systems management 
BIOS 
SOL – serial over LAN 
SPI – serial peripheral interface 
SSD – solid-state drive 
TB – tray backplane 
TDP – thermal design power 
TM – tray midplane 
TOR – top of rack 
TPM – trusted platform module 
TxD – transmit data 
U – rack unit 
UART – universal asynchronous 
receiver/transmitter 
UEFI – unified extensible firmware 
interface 
UL – Underwriters Laboratories 
UPS – uninterrupted power supply 
Vpp – voltage peak to peak 
WMI – Windows Management 
Interface 
 